(kicad_pcb
	(version 20260206)
	(generator "pcbnew")
	(generator_version "10.0")
	(general
		(thickness 1.6)
		(legacy_teardrops no)
	)
	(paper "A4")
	(title_block
		(title "Wiwynn_Tioga_Pass_MB.brd")
		(comment 1 "Tioga Pass / footprints 213-219 of 4770")
	)
	(layers
		(0 "F.Cu" signal "TOP")
		(4 "In1.Cu" signal "L2GND")
		(6 "In2.Cu" signal "L3")
		(8 "In3.Cu" signal "L4GND")
		(10 "In4.Cu" signal "L5")
		(12 "In5.Cu" signal "L6GND")
		(14 "In6.Cu" signal "L7VCC")
		(16 "In7.Cu" signal "L8VCC")
		(18 "In8.Cu" signal "L9GND")
		(20 "In9.Cu" signal "L10")
		(22 "In10.Cu" signal "L11GND")
		(24 "In11.Cu" signal "L12")
		(26 "In12.Cu" signal "L13GND")
		(2 "B.Cu" signal "BOTTOM")
		(9 "F.Adhes" user "F.Adhesive")
		(11 "B.Adhes" user "B.Adhesive")
		(13 "F.Paste" user "Package Geometry/Pastemask Top")
		(15 "B.Paste" user "Package Geometry/Pastemask Bottom")
		(5 "F.SilkS" user "Ref Des/Silkscreen Top")
		(7 "B.SilkS" user "Ref Des/Silkscreen Bottom")
		(1 "F.Mask" user "Board Geometry/Soldermask Top")
		(3 "B.Mask" user "Board Geometry/Soldermask Bottom")
		(17 "Dwgs.User" user "User.Drawings")
		(19 "Cmts.User" user "User.Comments")
		(21 "Eco1.User" user "User.Eco1")
		(23 "Eco2.User" user "User.Eco2")
		(25 "Edge.Cuts" user "Board Geometry/Outline")
		(27 "Margin" user)
		(31 "F.CrtYd" user "Package Geometry/Place Bound Top")
		(29 "B.CrtYd" user "Package Geometry/Place Bound Bottom")
		(35 "F.Fab" user "Ref Des/Assembly Top")
		(33 "B.Fab" user "Ref Des/Assembly Bottom")
	)
	(footprint ""
		(layer "F.Cu")
		(at 379.984 -88.2015)
		(property "Reference" "R3N24"
			(at 0 0 0)
			(layer "F.SilkS")
			(hide yes)
			(effects
				(font
					(size 1.27 1.27)
				)
			)
		)
		(property "Value" ""
			(at 0 0 0)
			(layer "F.Fab")
			(effects
				(font
					(size 1.27 1.27)
				)
			)
		)
		(duplicate_pad_numbers_are_jumpers no)
		(fp_poly
			(pts
				(xy -0.2794 -0.1016) (xy 0.2794 -0.1016) (xy 0.2794 0.9906) (xy -0.2794 0.9906)
			)
			(stroke
				(width 0)
				(type default)
			)
			(fill no)
			(layer "F.CrtYd")
		)
		(fp_line
			(start -0.2794 -0.1016)
			(end -0.2794 0.9906)
			(stroke
				(width 0.1)
				(type default)
			)
			(layer "F.Fab")
		)
		(fp_line
			(start -0.2794 0.9906)
			(end 0.2794 0.9906)
			(stroke
				(width 0.1)
				(type default)
			)
			(layer "F.Fab")
		)
		(fp_line
			(start 0.2794 -0.1016)
			(end -0.2794 -0.1016)
			(stroke
				(width 0.1)
				(type default)
			)
			(layer "F.Fab")
		)
		(fp_line
			(start 0.2794 0.9906)
			(end 0.2794 -0.1016)
			(stroke
				(width 0.1)
				(type default)
			)
			(layer "F.Fab")
		)
		(pad "1" smd rect
			(at 0 0)
			(size 0.508 0.508)
			(layers "F.Cu" "F.Mask" "F.Paste")
			(net "LPC_LAD2_IO2")
		)
		(pad "2" smd rect
			(at 0 0.889)
			(size 0.508 0.508)
			(layers "F.Cu" "F.Mask" "F.Paste")
			(net "LPC_LAD2_IO2_R")
		)
		(zone
			(layer "F.Cu")
			(hatch none 0.5)
			(connect_pads
				(clearance 0)
			)
			(min_thickness 0.25)
			(keepout
				(tracks allowed)
				(vias not_allowed)
				(pads allowed)
				(copperpour not_allowed)
				(footprints allowed)
			)
			(placement
				(enabled no)
				(sheetname "")
			)
			(fill
				(thermal_gap 0.5)
				(thermal_bridge_width 0.5)
				(island_removal_mode 0)
			)
			(polygon
				(pts
					(xy 379.73 -87.9475) (xy 380.238 -87.9475) (xy 380.238 -87.5665) (xy 379.73 -87.5665)
				)
			)
		)
		(zone
			(layer "F.Cu")
			(hatch none 0.5)
			(connect_pads
				(clearance 0)
			)
			(min_thickness 0.25)
			(keepout
				(tracks not_allowed)
				(vias allowed)
				(pads allowed)
				(copperpour not_allowed)
				(footprints allowed)
			)
			(placement
				(enabled no)
				(sheetname "")
			)
			(fill
				(thermal_gap 0.5)
				(thermal_bridge_width 0.5)
				(island_removal_mode 0)
			)
			(polygon
				(pts
					(xy 379.73 -87.5665) (xy 380.238 -87.5665) (xy 380.238 -87.9475) (xy 379.73 -87.9475)
				)
			)
		)
	)
	(footprint ""
		(layer "F.Cu")
		(at 198.87946 -30.861 180)
		(property "Reference" "C4F6"
			(at 0.75946 -3.83667 0)
			(unlocked yes)
			(layer "F.SilkS")
			(effects
				(font
					(size 0.7874 0.5842)
					(thickness 0.1524)
				)
			)
		)
		(property "Value" ""
			(at 0 0 180)
			(layer "F.Fab")
			(effects
				(font
					(size 1.27 1.27)
				)
			)
		)
		(duplicate_pad_numbers_are_jumpers no)
		(fp_line
			(start 5.1435 9.271)
			(end 1.4097 9.271)
			(stroke
				(width 0.1524)
				(type default)
			)
			(layer "F.SilkS")
		)
		(fp_line
			(start 5.1435 -0.127)
			(end 5.1435 9.271)
			(stroke
				(width 0.1524)
				(type default)
			)
			(layer "F.SilkS")
		)
		(fp_line
			(start 4.3815 -1.016)
			(end 5.1435 -0.127)
			(stroke
				(width 0.1524)
				(type default)
			)
			(layer "F.SilkS")
		)
		(fp_line
			(start 1.8415 2.0955)
			(end 1.4097 2.0955)
			(stroke
				(width 0.1524)
				(type default)
			)
			(layer "F.SilkS")
		)
		(fp_line
			(start 1.8415 -1.016)
			(end 4.3815 -1.016)
			(stroke
				(width 0.1524)
				(type default)
			)
			(layer "F.SilkS")
		)
		(fp_line
			(start 1.8415 -2.0955)
			(end 1.8415 2.0955)
			(stroke
				(width 0.1524)
				(type default)
			)
			(layer "F.SilkS")
		)
		(fp_line
			(start 1.4097 -2.0955)
			(end 1.8415 -2.0955)
			(stroke
				(width 0.1524)
				(type default)
			)
			(layer "F.SilkS")
		)
		(fp_line
			(start -1.4097 9.271)
			(end -5.1435 9.271)
			(stroke
				(width 0.1524)
				(type default)
			)
			(layer "F.SilkS")
		)
		(fp_line
			(start -1.4097 -2.0955)
			(end -1.8415 -2.0955)
			(stroke
				(width 0.1524)
				(type default)
			)
			(layer "F.SilkS")
		)
		(fp_line
			(start -1.8415 2.0955)
			(end -1.4097 2.0955)
			(stroke
				(width 0.1524)
				(type default)
			)
			(layer "F.SilkS")
		)
		(fp_line
			(start -1.8415 -2.0955)
			(end -1.8415 2.0955)
			(stroke
				(width 0.1524)
				(type default)
			)
			(layer "F.SilkS")
		)
		(fp_line
			(start -4.3815 -1.016)
			(end -1.8415 -1.016)
			(stroke
				(width 0.1524)
				(type default)
			)
			(layer "F.SilkS")
		)
		(fp_line
			(start -5.1435 9.271)
			(end -5.1435 -0.127)
			(stroke
				(width 0.1524)
				(type default)
			)
			(layer "F.SilkS")
		)
		(fp_line
			(start -5.1435 -0.127)
			(end -4.3815 -1.016)
			(stroke
				(width 0.1524)
				(type default)
			)
			(layer "F.SilkS")
		)
		(fp_poly
			(pts
				(xy -5.14604 -0.12954) (xy -4.38404 -1.01346) (xy 4.37896 -1.016) (xy 5.1435 -0.12954) (xy 5.14096 9.271)
				(xy -5.14604 9.27354)
			)
			(stroke
				(width 0)
				(type default)
			)
			(fill no)
			(layer "F.CrtYd")
		)
		(fp_line
			(start 5.1435 9.271)
			(end -5.1435 9.271)
			(stroke
				(width 0.1)
				(type default)
			)
			(layer "F.Fab")
		)
		(fp_line
			(start 5.1435 -0.127)
			(end 5.1435 9.271)
			(stroke
				(width 0.1)
				(type default)
			)
			(layer "F.Fab")
		)
		(fp_line
			(start 4.3815 -1.016)
			(end 5.1435 -0.127)
			(stroke
				(width 0.1)
				(type default)
			)
			(layer "F.Fab")
		)
		(fp_line
			(start -4.3815 -1.016)
			(end 4.3815 -1.016)
			(stroke
				(width 0.1)
				(type default)
			)
			(layer "F.Fab")
		)
		(fp_line
			(start -5.1435 9.271)
			(end -5.1435 -0.127)
			(stroke
				(width 0.1)
				(type default)
			)
			(layer "F.Fab")
		)
		(fp_line
			(start -5.1435 -0.127)
			(end -4.3815 -1.016)
			(stroke
				(width 0.1)
				(type default)
			)
			(layer "F.Fab")
		)
		(fp_circle
			(center 0 4.1275)
			(end -4.9911 4.1275)
			(stroke
				(width 0.1)
				(type default)
			)
			(fill no)
			(layer "F.Fab")
		)
		(pad "1" smd rect
			(at 0 0 180)
			(size 1.905 4.191)
			(layers "F.Cu" "F.Mask" "F.Paste")
			(net "P12V_STBY")
		)
		(pad "2" smd rect
			(at 0 8.255 180)
			(size 1.905 4.191)
			(layers "F.Cu" "F.Mask" "F.Paste")
			(net "GND")
		)
		(zone
			(layer "F.Cu")
			(hatch none 0.5)
			(connect_pads
				(clearance 0)
			)
			(min_thickness 0.25)
			(keepout
				(tracks allowed)
				(vias not_allowed)
				(pads allowed)
				(copperpour not_allowed)
				(footprints allowed)
			)
			(placement
				(enabled no)
				(sheetname "")
			)
			(fill
				(thermal_gap 0.5)
				(thermal_bridge_width 0.5)
				(island_removal_mode 0)
			)
			(polygon
				(pts
					(xy 204.02296 -40.132) (xy 193.73596 -40.132) (xy 193.73596 -30.734) (xy 194.49796 -29.845) (xy 203.26096 -29.845)
					(xy 204.02296 -30.734)
				)
			)
		)
	)
	(footprint ""
		(layer "F.Cu")
		(at 399.67408 -155.08986)
		(property "Reference" "R8W3"
			(at -0.8382 -0.67818 0)
			(unlocked yes)
			(layer "F.SilkS")
			(effects
				(font
					(size 0.4064 0.254)
					(thickness 0.1524)
				)
				(justify left)
			)
		)
		(property "Value" ""
			(at 0 0 0)
			(layer "F.Fab")
			(effects
				(font
					(size 1.27 1.27)
				)
			)
		)
		(duplicate_pad_numbers_are_jumpers no)
		(fp_poly
			(pts
				(xy -0.2794 -0.1016) (xy 0.2794 -0.1016) (xy 0.2794 0.9906) (xy -0.2794 0.9906)
			)
			(stroke
				(width 0)
				(type default)
			)
			(fill no)
			(layer "F.CrtYd")
		)
		(fp_line
			(start -0.2794 -0.1016)
			(end -0.2794 0.9906)
			(stroke
				(width 0.1)
				(type default)
			)
			(layer "F.Fab")
		)
		(fp_line
			(start -0.2794 0.9906)
			(end 0.2794 0.9906)
			(stroke
				(width 0.1)
				(type default)
			)
			(layer "F.Fab")
		)
		(fp_line
			(start 0.2794 -0.1016)
			(end -0.2794 -0.1016)
			(stroke
				(width 0.1)
				(type default)
			)
			(layer "F.Fab")
		)
		(fp_line
			(start 0.2794 0.9906)
			(end 0.2794 -0.1016)
			(stroke
				(width 0.1)
				(type default)
			)
			(layer "F.Fab")
		)
		(pad "1" smd rect
			(at 0 0)
			(size 0.508 0.508)
			(layers "F.Cu" "F.Mask" "F.Paste")
			(net "VR_PVNN_P1V05_PCH_VD12")
		)
		(pad "2" smd rect
			(at 0 0.889)
			(size 0.508 0.508)
			(layers "F.Cu" "F.Mask" "F.Paste")
			(net "PU_PVNN_PCH_VDIO")
		)
		(zone
			(layer "F.Cu")
			(hatch none 0.5)
			(connect_pads
				(clearance 0)
			)
			(min_thickness 0.25)
			(keepout
				(tracks allowed)
				(vias not_allowed)
				(pads allowed)
				(copperpour not_allowed)
				(footprints allowed)
			)
			(placement
				(enabled no)
				(sheetname "")
			)
			(fill
				(thermal_gap 0.5)
				(thermal_bridge_width 0.5)
				(island_removal_mode 0)
			)
			(polygon
				(pts
					(xy 399.42008 -154.83586) (xy 399.92808 -154.83586) (xy 399.92808 -154.45486) (xy 399.42008 -154.45486)
				)
			)
		)
		(zone
			(layer "F.Cu")
			(hatch none 0.5)
			(connect_pads
				(clearance 0)
			)
			(min_thickness 0.25)
			(keepout
				(tracks not_allowed)
				(vias allowed)
				(pads allowed)
				(copperpour not_allowed)
				(footprints allowed)
			)
			(placement
				(enabled no)
				(sheetname "")
			)
			(fill
				(thermal_gap 0.5)
				(thermal_bridge_width 0.5)
				(island_removal_mode 0)
			)
			(polygon
				(pts
					(xy 399.42008 -154.45486) (xy 399.92808 -154.45486) (xy 399.92808 -154.83586) (xy 399.42008 -154.83586)
				)
			)
		)
	)
	(footprint ""
		(layer "F.Cu")
		(at 192.685162 -125.774958 180)
		(property "Reference" "R4B12"
			(at 0 0 180)
			(layer "F.SilkS")
			(hide yes)
			(effects
				(font
					(size 1.27 1.27)
				)
			)
		)
		(property "Value" ""
			(at 0 0 180)
			(layer "F.Fab")
			(effects
				(font
					(size 1.27 1.27)
				)
			)
		)
		(duplicate_pad_numbers_are_jumpers no)
		(fp_line
			(start 0.9017 1.952498)
			(end 0.9017 0.853948)
			(stroke
				(width 0.1524)
				(type default)
			)
			(layer "F.SilkS")
		)
		(fp_line
			(start -0.9017 1.951736)
			(end -0.9017 0.823468)
			(stroke
				(width 0.1524)
				(type default)
			)
			(layer "F.SilkS")
		)
		(fp_rect
			(start -0.9017 3.0988)
			(end 0.9017 -0.3048)
			(stroke
				(width 0)
				(type default)
			)
			(fill no)
			(layer "F.CrtYd")
		)
		(fp_line
			(start 0.9017 3.0988)
			(end 0.9017 -0.3048)
			(stroke
				(width 0.1)
				(type default)
			)
			(layer "F.Fab")
		)
		(fp_line
			(start 0.9017 -0.3048)
			(end -0.9017 -0.3048)
			(stroke
				(width 0.1)
				(type default)
			)
			(layer "F.Fab")
		)
		(fp_line
			(start -0.9017 3.0988)
			(end 0.9017 3.0988)
			(stroke
				(width 0.1)
				(type default)
			)
			(layer "F.Fab")
		)
		(fp_line
			(start -0.9017 -0.3048)
			(end -0.9017 3.0988)
			(stroke
				(width 0.1)
				(type default)
			)
			(layer "F.Fab")
		)
		(pad "1" smd rect
			(at 0 0 180)
			(size 1.524 1.016)
			(layers "F.Cu" "F.Mask" "F.Paste")
			(net "P12V_STBY")
		)
		(pad "2" smd rect
			(at 0 2.794 180)
			(size 1.524 1.016)
			(layers "F.Cu" "F.Mask" "F.Paste")
			(net "P12V_NVDIMM_DEF")
		)
		(zone
			(layer "F.Cu")
			(hatch none 0.5)
			(connect_pads
				(clearance 0)
			)
			(min_thickness 0.25)
			(keepout
				(tracks allowed)
				(vias not_allowed)
				(pads allowed)
				(copperpour not_allowed)
				(footprints allowed)
			)
			(placement
				(enabled no)
				(sheetname "")
			)
			(fill
				(thermal_gap 0.5)
				(thermal_bridge_width 0.5)
				(island_removal_mode 0)
			)
			(polygon
				(pts
					(xy 193.447162 -128.060958) (xy 191.923162 -128.060958) (xy 191.923162 -126.282958) (xy 193.447162 -126.282958)
				)
			)
		)
	)
	(footprint ""
		(layer "F.Cu")
		(at 433.084986 -21.505672 -90)
		(property "Reference" "U10W1"
			(at -0.14986 2.621788 270)
			(unlocked yes)
			(layer "F.SilkS")
			(effects
				(font
					(size 1.27 0.964946)
					(thickness 0.000001)
				)
				(justify left)
			)
		)
		(property "Value" ""
			(at 0 0 270)
			(layer "F.Fab")
			(effects
				(font
					(size 1.27 1.27)
				)
			)
		)
		(duplicate_pad_numbers_are_jumpers no)
		(fp_circle
			(center -0.4699 -0.8382)
			(end -0.4699 -0.9652)
			(stroke
				(width 0.254)
				(type default)
			)
			(fill no)
			(layer "F.SilkS")
		)
		(fp_poly
			(pts
				(xy 0.21463 -0.450088) (xy 1.56337 -0.450088) (xy 1.56337 1.75006) (xy 0.21463 1.75006)
			)
			(stroke
				(width 0)
				(type default)
			)
			(fill no)
			(layer "F.CrtYd")
		)
		(fp_line
			(start 0.21463 1.75006)
			(end 0.21463 -0.450088)
			(stroke
				(width 0.1)
				(type default)
			)
			(layer "F.Fab")
		)
		(fp_line
			(start 1.56337 1.75006)
			(end 0.21463 1.75006)
			(stroke
				(width 0.1)
				(type default)
			)
			(layer "F.Fab")
		)
		(fp_line
			(start 0.21463 -0.450088)
			(end 1.56337 -0.450088)
			(stroke
				(width 0.1)
				(type default)
			)
			(layer "F.Fab")
		)
		(fp_line
			(start 1.56337 -0.450088)
			(end 1.56337 1.75006)
			(stroke
				(width 0.1)
				(type default)
			)
			(layer "F.Fab")
		)
		(fp_circle
			(center -0.4699 -0.8382)
			(end -0.4699 -0.9652)
			(stroke
				(width 0.254)
				(type default)
			)
			(fill no)
			(layer "F.Fab")
		)
		(pad "1" smd rect
			(at 0 0 270)
			(size 1.016 0.381)
			(layers "F.Cu" "F.Mask" "F.Paste")
			(net "Net_6482")
		)
		(pad "2" smd rect
			(at 0 0.649986 270)
			(size 1.016 0.381)
			(layers "F.Cu" "F.Mask" "F.Paste")
			(net "PUMP_PWM_OUT")
		)
		(pad "3" smd rect
			(at 0 1.299972 270)
			(size 1.016 0.381)
			(layers "F.Cu" "F.Mask" "F.Paste")
			(net "GND")
		)
		(pad "4" smd rect
			(at 1.778 1.299972 270)
			(size 1.016 0.381)
			(layers "F.Cu" "F.Mask" "F.Paste")
			(net "PUMP_PWM_OUT_BUF")
		)
		(pad "5" smd rect
			(at 1.778 0 270)
			(size 1.016 0.381)
			(layers "F.Cu" "F.Mask" "F.Paste")
			(net "P3V3_STBY")
		)
	)
	(footprint ""
		(layer "F.Cu")
		(at 339.2932 -29.6672 -90)
		(property "Reference" "L7F1"
			(at -4.08813 5.7658 0)
			(unlocked yes)
			(layer "F.SilkS")
			(effects
				(font
					(size 0.7874 0.5842)
					(thickness 0.1524)
				)
				(justify left)
			)
		)
		(property "Value" ""
			(at 0 0 270)
			(layer "F.Fab")
			(effects
				(font
					(size 1.27 1.27)
				)
			)
		)
		(duplicate_pad_numbers_are_jumpers no)
		(fp_line
			(start -3.4036 6.1341)
			(end -3.4036 -0.6731)
			(stroke
				(width 0.1524)
				(type default)
			)
			(layer "F.SilkS")
		)
		(fp_line
			(start -2.5654 6.1341)
			(end -3.4036 6.1341)
			(stroke
				(width 0.1524)
				(type default)
			)
			(layer "F.SilkS")
		)
		(fp_line
			(start 3.4036 6.1341)
			(end 2.5654 6.1341)
			(stroke
				(width 0.1524)
				(type default)
			)
			(layer "F.SilkS")
		)
		(fp_line
			(start -3.4036 -0.6731)
			(end -2.5654 -0.6731)
			(stroke
				(width 0.1524)
				(type default)
			)
			(layer "F.SilkS")
		)
		(fp_line
			(start 2.5654 -0.6731)
			(end 3.4036 -0.6731)
			(stroke
				(width 0.1524)
				(type default)
			)
			(layer "F.SilkS")
		)
		(fp_line
			(start 3.4036 -0.6731)
			(end 3.4036 6.1341)
			(stroke
				(width 0.1524)
				(type default)
			)
			(layer "F.SilkS")
		)
		(fp_rect
			(start 3.4036 6.1341)
			(end -3.4036 -0.6731)
			(stroke
				(width 0)
				(type default)
			)
			(fill no)
			(layer "F.CrtYd")
		)
		(fp_line
			(start -3.4036 6.1341)
			(end -3.4036 -0.6731)
			(stroke
				(width 0.1)
				(type default)
			)
			(layer "F.Fab")
		)
		(fp_line
			(start 3.4036 6.1341)
			(end -3.4036 6.1341)
			(stroke
				(width 0.1)
				(type default)
			)
			(layer "F.Fab")
		)
		(fp_line
			(start -3.4036 -0.6731)
			(end 3.4036 -0.6731)
			(stroke
				(width 0.1)
				(type default)
			)
			(layer "F.Fab")
		)
		(fp_line
			(start 3.4036 -0.6731)
			(end 3.4036 6.1341)
			(stroke
				(width 0.1)
				(type default)
			)
			(layer "F.Fab")
		)
		(pad "1" smd rect
			(at 0 0 270)
			(size 3.556 3.175)
			(layers "F.Cu" "F.Mask" "F.Paste")
			(net "VR_PVPP_ABC_PHASE")
		)
		(pad "2" smd rect
			(at 0 5.461 270)
			(size 3.556 3.175)
			(layers "F.Cu" "F.Mask" "F.Paste")
			(net "PVPP_ABC")
		)
	)
	(footprint ""
		(layer "F.Cu")
		(at 320.296032 -12.954 90)
		(property "Reference" "C6G2"
			(at 0 0 90)
			(layer "F.SilkS")
			(hide yes)
			(effects
				(font
					(size 1.27 1.27)
				)
			)
		)
		(property "Value" ""
			(at 0 0 90)
			(layer "F.Fab")
			(effects
				(font
					(size 1.27 1.27)
				)
			)
		)
		(duplicate_pad_numbers_are_jumpers no)
		(fp_poly
			(pts
				(xy -0.4953 -0.2032) (xy 0.4953 -0.2032) (xy 0.4953 1.6002) (xy -0.4953 1.6002)
			)
			(stroke
				(width 0)
				(type default)
			)
			(fill no)
			(layer "F.CrtYd")
		)
		(fp_line
			(start 0.4953 -0.2032)
			(end 0.4953 1.6002)
			(stroke
				(width 0.1)
				(type default)
			)
			(layer "F.Fab")
		)
		(fp_line
			(start -0.4953 -0.2032)
			(end 0.4953 -0.2032)
			(stroke
				(width 0.1)
				(type default)
			)
			(layer "F.Fab")
		)
		(fp_line
			(start 0.4953 1.6002)
			(end -0.4953 1.6002)
			(stroke
				(width 0.1)
				(type default)
			)
			(layer "F.Fab")
		)
		(fp_line
			(start -0.4953 1.6002)
			(end -0.4953 -0.2032)
			(stroke
				(width 0.1)
				(type default)
			)
			(layer "F.Fab")
		)
		(pad "1" smd rect
			(at 0 0 90)
			(size 0.762 0.889)
			(layers "F.Cu" "F.Mask" "F.Paste")
			(net "PVPP_ABC")
		)
		(pad "2" smd rect
			(at 0 1.397 90)
			(size 0.762 0.889)
			(layers "F.Cu" "F.Mask" "F.Paste")
			(net "GND")
		)
		(zone
			(layer "F.Cu")
			(hatch none 0.5)
			(connect_pads
				(clearance 0)
			)
			(min_thickness 0.25)
			(keepout
				(tracks not_allowed)
				(vias allowed)
				(pads allowed)
				(copperpour not_allowed)
				(footprints allowed)
			)
			(placement
				(enabled no)
				(sheetname "")
			)
			(fill
				(thermal_gap 0.5)
				(thermal_bridge_width 0.5)
				(island_removal_mode 0)
			)
			(polygon
				(pts
					(xy 320.740532 -12.573) (xy 320.740532 -13.335) (xy 321.248532 -13.335) (xy 321.248532 -12.573)
				)
			)
		)
	)
)
